(kicad_pcb
	(version 20260206)
	(generator "pcbnew")
	(generator_version "10.0")
	(general
		(thickness 1.6)
		(legacy_teardrops no)
	)
	(paper "A4")
	(title_block
		(title "03242023_DA0F0TMBIJ0_F0T_Motherboard_J_brd_V01_OCP.brd")
		(comment 1 "Grand Teton / footprints 2054-2058 of 6105")
	)
	(layers
		(0 "F.Cu" signal "TOP")
		(4 "In1.Cu" signal "GND")
		(6 "In2.Cu" signal "IN1")
		(8 "In3.Cu" signal "GND1")
		(10 "In4.Cu" signal "IN2")
		(12 "In5.Cu" signal "GND2")
		(14 "In6.Cu" signal "IN3")
		(16 "In7.Cu" signal "GND3")
		(18 "In8.Cu" signal "VCC")
		(20 "In9.Cu" signal "VCC1")
		(22 "In10.Cu" signal "GND4")
		(24 "In11.Cu" signal "IN4")
		(26 "In12.Cu" signal "GND5")
		(28 "In13.Cu" signal "IN5")
		(30 "In14.Cu" signal "GND6")
		(32 "In15.Cu" signal "IN6")
		(34 "In16.Cu" signal "GND7")
		(2 "B.Cu" signal "BOTTOM")
		(9 "F.Adhes" user "F.Adhesive")
		(11 "B.Adhes" user "B.Adhesive")
		(13 "F.Paste" user "Package Geometry/Pastemask Top")
		(15 "B.Paste" user "Package Geometry/Pastemask Bottom")
		(5 "F.SilkS" user "Ref Des/Silkscreen Top")
		(7 "B.SilkS" user "Ref Des/Silkscreen Bottom")
		(1 "F.Mask" user "Board Geometry/Soldermask Top")
		(3 "B.Mask" user "Board Geometry/Soldermask Bottom")
		(17 "Dwgs.User" user "User.Drawings")
		(19 "Cmts.User" user "User.Comments")
		(21 "Eco1.User" user "User.Eco1")
		(23 "Eco2.User" user "User.Eco2")
		(25 "Edge.Cuts" user "Board Geometry/Outline")
		(27 "Margin" user)
		(31 "F.CrtYd" user "Package Geometry/Place Bound Top")
		(29 "B.CrtYd" user "Package Geometry/Place Bound Bottom")
		(35 "F.Fab" user "Ref Des/Assembly Top")
		(33 "B.Fab" user "Ref Des/Assembly Bottom")
	)
	(footprint ""
		(layer "F.Cu")
		(at 460.6798 -380.691898 90)
		(property "Reference" "PR73"
			(at 0 0 90)
			(layer "F.SilkS")
			(hide yes)
			(effects
				(font
					(size 1.27 1.27)
				)
			)
		)
		(property "Value" ""
			(at 0 0 90)
			(layer "F.Fab")
			(effects
				(font
					(size 1.27 1.27)
				)
			)
		)
		(duplicate_pad_numbers_are_jumpers no)
		(fp_line
			(start 0.7874 -0.4064)
			(end 0.7874 0.4064)
			(stroke
				(width 0.1524)
				(type default)
			)
			(layer "F.SilkS")
		)
		(fp_line
			(start -0.7874 -0.4064)
			(end 0.7874 -0.4064)
			(stroke
				(width 0.1524)
				(type default)
			)
			(layer "F.SilkS")
		)
		(fp_line
			(start 0.7874 0.4064)
			(end -0.7874 0.4064)
			(stroke
				(width 0.1524)
				(type default)
			)
			(layer "F.SilkS")
		)
		(fp_line
			(start -0.7874 0.4064)
			(end -0.7874 -0.4064)
			(stroke
				(width 0.1524)
				(type default)
			)
			(layer "F.SilkS")
		)
		(fp_line
			(start -0.12065 -0.305054)
			(end -0.12065 -0.2794)
			(stroke
				(width 0.1)
				(type default)
			)
			(layer "F.Fab")
		)
		(fp_line
			(start -0.67945 -0.305054)
			(end -0.12065 -0.305054)
			(stroke
				(width 0.1)
				(type default)
			)
			(layer "F.Fab")
		)
		(fp_line
			(start 0.67945 -0.3048)
			(end 0.67945 0.3048)
			(stroke
				(width 0.1)
				(type default)
			)
			(layer "F.Fab")
		)
		(fp_line
			(start 0.12065 -0.3048)
			(end 0.67945 -0.3048)
			(stroke
				(width 0.1)
				(type default)
			)
			(layer "F.Fab")
		)
		(fp_line
			(start 0.12065 -0.2794)
			(end 0.12065 -0.3048)
			(stroke
				(width 0.1)
				(type default)
			)
			(layer "F.Fab")
		)
		(fp_line
			(start -0.12065 -0.2794)
			(end 0.12065 -0.2794)
			(stroke
				(width 0.1)
				(type default)
			)
			(layer "F.Fab")
		)
		(fp_line
			(start 0.120396 0.2794)
			(end -0.12065 0.2794)
			(stroke
				(width 0.1)
				(type default)
			)
			(layer "F.Fab")
		)
		(fp_line
			(start -0.12065 0.2794)
			(end -0.12065 0.3048)
			(stroke
				(width 0.1)
				(type default)
			)
			(layer "F.Fab")
		)
		(fp_line
			(start 0.67945 0.3048)
			(end 0.120396 0.3048)
			(stroke
				(width 0.1)
				(type default)
			)
			(layer "F.Fab")
		)
		(fp_line
			(start 0.120396 0.3048)
			(end 0.120396 0.2794)
			(stroke
				(width 0.1)
				(type default)
			)
			(layer "F.Fab")
		)
		(fp_line
			(start -0.12065 0.3048)
			(end -0.67945 0.3048)
			(stroke
				(width 0.1)
				(type default)
			)
			(layer "F.Fab")
		)
		(fp_line
			(start -0.67945 0.3048)
			(end -0.67945 -0.305054)
			(stroke
				(width 0.1)
				(type default)
			)
			(layer "F.Fab")
		)
		(pad "1" smd circle
			(at -0.40005 0 90)
			(size 0 0)
			(layers "F.Cu" "F.Mask" "F.Paste")
			(net "P3V3_AUX")
		)
		(pad "2" smd circle
			(at 0.40005 0 90)
			(size 0 0)
			(layers "F.Cu" "F.Mask" "F.Paste")
			(net "PWRGD_P3V3_AUX")
		)
	)
	(footprint ""
		(layer "F.Cu")
		(at 163.50615 -418.514276 90)
		(property "Reference" "R3106"
			(at 0 0 90)
			(layer "F.SilkS")
			(hide yes)
			(effects
				(font
					(size 1.27 1.27)
				)
			)
		)
		(property "Value" ""
			(at 0 0 90)
			(layer "F.Fab")
			(effects
				(font
					(size 1.27 1.27)
				)
			)
		)
		(duplicate_pad_numbers_are_jumpers no)
		(fp_line
			(start 0.7874 -0.4064)
			(end 0.7874 0.4064)
			(stroke
				(width 0.1524)
				(type default)
			)
			(layer "F.SilkS")
		)
		(fp_line
			(start -0.7874 -0.4064)
			(end 0.7874 -0.4064)
			(stroke
				(width 0.1524)
				(type default)
			)
			(layer "F.SilkS")
		)
		(fp_line
			(start 0.7874 0.4064)
			(end -0.7874 0.4064)
			(stroke
				(width 0.1524)
				(type default)
			)
			(layer "F.SilkS")
		)
		(fp_line
			(start -0.7874 0.4064)
			(end -0.7874 -0.4064)
			(stroke
				(width 0.1524)
				(type default)
			)
			(layer "F.SilkS")
		)
		(fp_line
			(start -0.12065 -0.305054)
			(end -0.12065 -0.2794)
			(stroke
				(width 0.1)
				(type default)
			)
			(layer "F.Fab")
		)
		(fp_line
			(start -0.67945 -0.305054)
			(end -0.12065 -0.305054)
			(stroke
				(width 0.1)
				(type default)
			)
			(layer "F.Fab")
		)
		(fp_line
			(start 0.67945 -0.3048)
			(end 0.67945 0.3048)
			(stroke
				(width 0.1)
				(type default)
			)
			(layer "F.Fab")
		)
		(fp_line
			(start 0.12065 -0.3048)
			(end 0.67945 -0.3048)
			(stroke
				(width 0.1)
				(type default)
			)
			(layer "F.Fab")
		)
		(fp_line
			(start 0.12065 -0.2794)
			(end 0.12065 -0.3048)
			(stroke
				(width 0.1)
				(type default)
			)
			(layer "F.Fab")
		)
		(fp_line
			(start -0.12065 -0.2794)
			(end 0.12065 -0.2794)
			(stroke
				(width 0.1)
				(type default)
			)
			(layer "F.Fab")
		)
		(fp_line
			(start 0.120396 0.2794)
			(end -0.12065 0.2794)
			(stroke
				(width 0.1)
				(type default)
			)
			(layer "F.Fab")
		)
		(fp_line
			(start -0.12065 0.2794)
			(end -0.12065 0.3048)
			(stroke
				(width 0.1)
				(type default)
			)
			(layer "F.Fab")
		)
		(fp_line
			(start 0.67945 0.3048)
			(end 0.120396 0.3048)
			(stroke
				(width 0.1)
				(type default)
			)
			(layer "F.Fab")
		)
		(fp_line
			(start 0.120396 0.3048)
			(end 0.120396 0.2794)
			(stroke
				(width 0.1)
				(type default)
			)
			(layer "F.Fab")
		)
		(fp_line
			(start -0.12065 0.3048)
			(end -0.67945 0.3048)
			(stroke
				(width 0.1)
				(type default)
			)
			(layer "F.Fab")
		)
		(fp_line
			(start -0.67945 0.3048)
			(end -0.67945 -0.305054)
			(stroke
				(width 0.1)
				(type default)
			)
			(layer "F.Fab")
		)
		(pad "1" smd circle
			(at -0.40005 0 90)
			(size 0 0)
			(layers "F.Cu" "F.Mask" "F.Paste")
			(net "SMB_BMC_SWB_SDA")
		)
		(pad "2" smd circle
			(at 0.40005 0 90)
			(size 0 0)
			(layers "F.Cu" "F.Mask" "F.Paste")
			(net "SMB_BMC_SWB_R_SDA")
		)
	)
	(footprint ""
		(layer "F.Cu")
		(at 88.837262 -337.126326)
		(property "Reference" "PU25_P1_6"
			(at -2.0955 -6.41985 0)
			(unlocked yes)
			(layer "F.SilkS")
			(effects
				(font
					(size 0.7874 0.5842)
					(thickness 0.1524)
				)
				(justify left)
			)
		)
		(property "Value" ""
			(at 0 0 0)
			(layer "F.Fab")
			(effects
				(font
					(size 1.27 1.27)
				)
			)
		)
		(duplicate_pad_numbers_are_jumpers no)
		(fp_line
			(start -2.500122 -2.999994)
			(end -2.24409 -2.999994)
			(stroke
				(width 0.1524)
				(type default)
			)
			(layer "F.SilkS")
		)
		(fp_line
			(start -2.500122 -2.529078)
			(end -2.500122 -2.999994)
			(stroke
				(width 0.1524)
				(type default)
			)
			(layer "F.SilkS")
		)
		(fp_line
			(start -2.500122 0.6604)
			(end -2.500122 0.229108)
			(stroke
				(width 0.1524)
				(type default)
			)
			(layer "F.SilkS")
		)
		(fp_line
			(start -2.500122 2.999994)
			(end -2.500122 2.339594)
			(stroke
				(width 0.1524)
				(type default)
			)
			(layer "F.SilkS")
		)
		(fp_line
			(start -2.2987 2.999994)
			(end -2.500122 2.999994)
			(stroke
				(width 0.1524)
				(type default)
			)
			(layer "F.SilkS")
		)
		(fp_line
			(start 2.31394 -2.999994)
			(end 2.500122 -2.999994)
			(stroke
				(width 0.1524)
				(type default)
			)
			(layer "F.SilkS")
		)
		(fp_line
			(start 2.500122 -2.999994)
			(end 2.500122 -2.44348)
			(stroke
				(width 0.1524)
				(type default)
			)
			(layer "F.SilkS")
		)
		(fp_line
			(start 2.500122 2.339594)
			(end 2.500122 2.999994)
			(stroke
				(width 0.1524)
				(type default)
			)
			(layer "F.SilkS")
		)
		(fp_line
			(start 2.500122 2.999994)
			(end 2.2987 2.999994)
			(stroke
				(width 0.1524)
				(type default)
			)
			(layer "F.SilkS")
		)
		(fp_poly
			(pts
				(xy -2.209546 -3.690112) (xy -2.717546 -2.674112) (xy -3.225546 -3.690112)
			)
			(stroke
				(width 0)
				(type default)
			)
			(fill yes)
			(layer "F.SilkS")
		)
		(fp_line
			(start -2.500122 -2.999994)
			(end 2.500122 -2.999994)
			(stroke
				(width 0.1)
				(type default)
			)
			(layer "F.Fab")
		)
		(fp_line
			(start -2.500122 2.999994)
			(end -2.500122 -2.999994)
			(stroke
				(width 0.1)
				(type default)
			)
			(layer "F.Fab")
		)
		(fp_line
			(start 2.500122 -2.999994)
			(end 2.500122 2.999994)
			(stroke
				(width 0.1)
				(type default)
			)
			(layer "F.Fab")
		)
		(fp_line
			(start 2.500122 2.999994)
			(end -2.500122 2.999994)
			(stroke
				(width 0.1)
				(type default)
			)
			(layer "F.Fab")
		)
		(fp_poly
			(pts
				(xy -4.218432 -2.783078) (xy -4.218432 -1.767078) (xy -3.202432 -2.275078)
			)
			(stroke
				(width 0)
				(type default)
			)
			(fill yes)
			(layer "F.Fab")
		)
		(pad "1" smd rect
			(at -2.400046 -2.275078 90)
			(size 0.2286 0.6096)
			(layers "F.Cu" "F.Mask" "F.Paste")
			(net "PVCCIN_CPU1_VOS6")
		)
		(pad "2" smd rect
			(at -2.400046 -1.82499 90)
			(size 0.2286 0.6096)
			(layers "F.Cu" "F.Mask" "F.Paste")
			(net "GND")
		)
		(pad "3" smd rect
			(at -2.400046 -1.374902 90)
			(size 0.2286 0.6096)
			(layers "F.Cu" "F.Mask" "F.Paste")
			(net "PVCCIN_CPU1_VDD6")
		)
		(pad "4" smd rect
			(at -2.400046 -0.925068 90)
			(size 0.2286 0.6096)
			(layers "F.Cu" "F.Mask" "F.Paste")
			(net "PVCCIN_CPU1_PVCC")
		)
		(pad "5" smd rect
			(at -2.400046 -0.47498 90)
			(size 0.2286 0.6096)
			(layers "F.Cu" "F.Mask" "F.Paste")
			(net "GND")
		)
		(pad "6" smd rect
			(at -2.400046 -0.024892 90)
			(size 0.2286 0.6096)
			(layers "F.Cu" "F.Mask" "F.Paste")
			(net "Net_8535")
		)
		(pad "7_9-20_24" smd circle
			(at 0 1.150112 90)
			(size 0 0)
			(layers "F.Cu" "F.Mask" "F.Paste")
			(net "GND")
		)
		(pad "10_19" smd rect
			(at 0 2.899918 90)
			(size 0.6096 4.318)
			(layers "F.Cu" "F.Mask" "F.Paste")
			(net "SW_PVCCIN_CPU1_SW6")
		)
		(pad "25_29" smd rect
			(at 1.549908 -1.279906 270)
			(size 2.0574 2.3114)
			(layers "F.Cu" "F.Mask" "F.Paste")
			(net "SW_P12V_PVCCIN_CPU1_FLT")
		)
		(pad "30" smd rect
			(at 2.05994 -2.899918)
			(size 0.2286 0.6096)
			(layers "F.Cu" "F.Mask" "F.Paste")
			(net "SW_P12V_PVCCIN_CPU1_FLT")
		)
		(pad "31" smd rect
			(at 1.610106 -2.899918)
			(size 0.2286 0.6096)
			(layers "F.Cu" "F.Mask" "F.Paste")
			(net "Net_8536")
		)
		(pad "32" smd rect
			(at 1.160018 -2.899918)
			(size 0.2286 0.6096)
			(layers "F.Cu" "F.Mask" "F.Paste")
			(net "SW_PVCCIN_CPU1_BOOTR6")
		)
		(pad "33" smd rect
			(at 0.70993 -2.899918)
			(size 0.2286 0.6096)
			(layers "F.Cu" "F.Mask" "F.Paste")
			(net "SW_PVCCIN_CPU1_BOOT6")
		)
		(pad "34" smd rect
			(at 0.260096 -2.899918)
			(size 0.2286 0.6096)
			(layers "F.Cu" "F.Mask" "F.Paste")
			(net "PVCCIN_CPU1_PWM6")
		)
		(pad "35" smd rect
			(at -0.189992 -2.899918)
			(size 0.2286 0.6096)
			(layers "F.Cu" "F.Mask" "F.Paste")
			(net "PVCCIN_CPU1_VDD6")
		)
		(pad "36" smd rect
			(at -0.64008 -2.899918)
			(size 0.2286 0.6096)
			(layers "F.Cu" "F.Mask" "F.Paste")
			(net "PVCCIN_CPU1_ATSEN")
		)
		(pad "37" smd rect
			(at -1.089914 -2.899918)
			(size 0.2286 0.6096)
			(layers "F.Cu" "F.Mask" "F.Paste")
			(net "PVCCIN_CPU1_LSET6")
		)
		(pad "38" smd rect
			(at -1.540002 -2.899918)
			(size 0.2286 0.6096)
			(layers "F.Cu" "F.Mask" "F.Paste")
			(net "PVCCIN_CPU1_IMON6")
		)
		(pad "39" smd rect
			(at -1.99009 -2.899918)
			(size 0.2286 0.6096)
			(layers "F.Cu" "F.Mask" "F.Paste")
			(net "PVCCIN_CPU1_VREF")
		)
		(pad "40" smd rect
			(at -0.87503 -1.27508)
			(size 1.7526 1.9558)
			(layers "F.Cu" "F.Mask" "F.Paste")
			(net "GND")
		)
		(pad "41" smd rect
			(at -1.525016 0.249936 270)
			(size 0.3048 0.4572)
			(layers "F.Cu" "F.Mask" "F.Paste")
			(net "Net_8534")
		)
		(zone
			(layer "F.Cu")
			(hatch none 0.5)
			(connect_pads
				(clearance 0)
			)
			(min_thickness 0.25)
			(keepout
				(tracks not_allowed)
				(vias allowed)
				(pads allowed)
				(copperpour not_allowed)
				(footprints allowed)
			)
			(placement
				(enabled no)
				(sheetname "")
			)
			(fill
				(thermal_gap 0.5)
				(thermal_bridge_width 0.5)
				(island_removal_mode 0)
			)
			(polygon
				(pts
					(xy 86.33714 -334.126332) (xy 86.33714 -334.875632) (xy 91.337384 -334.875632) (xy 91.337384 -334.126332)
					(xy 91.047062 -334.126332) (xy 91.047062 -334.582008) (xy 86.627462 -334.582008) (xy 86.627462 -334.126332)
				)
			)
		)
		(zone
			(layer "F.Cu")
			(hatch none 0.5)
			(connect_pads
				(clearance 0)
			)
			(min_thickness 0.25)
			(keepout
				(tracks not_allowed)
				(vias allowed)
				(pads allowed)
				(copperpour not_allowed)
				(footprints allowed)
			)
			(placement
				(enabled no)
				(sheetname "")
			)
			(fill
				(thermal_gap 0.5)
				(thermal_bridge_width 0.5)
				(island_removal_mode 0)
			)
			(polygon
				(pts
					(xy 86.792816 -337.464908) (xy 87.035132 -337.464908) (xy 87.035132 -337.372706) (xy 87.82812 -337.372706)
					(xy 87.82812 -337.035648) (xy 87.88654 -337.035648) (xy 87.88654 -336.377026) (xy 86.33714 -336.377026)
					(xy 86.33714 -336.833718) (xy 87.032846 -336.833718) (xy 87.032846 -336.67319) (xy 87.591646 -336.67319)
					(xy 87.591646 -337.07959) (xy 87.032846 -337.07959) (xy 87.032846 -336.859118) (xy 86.33714 -336.859118)
					(xy 86.33714 -336.986118) (xy 86.792816 -336.986118)
				)
			)
		)
	)
	(footprint ""
		(layer "F.Cu")
		(at 28.337002 -135.001 180)
		(property "Reference" "PJ51"
			(at 4.60756 -0.056896 0)
			(unlocked yes)
			(layer "F.SilkS")
			(effects
				(font
					(size 0.7874 0.5842)
					(thickness 0.1524)
				)
				(justify left)
			)
		)
		(property "Value" ""
			(at 0 0 180)
			(layer "F.Fab")
			(effects
				(font
					(size 1.27 1.27)
				)
			)
		)
		(duplicate_pad_numbers_are_jumpers no)
		(pad "1" smd circle
			(at -0.7493 0 270)
			(size 0 0)
			(layers "F.Cu" "F.Mask" "F.Paste")
			(net "VSENSE_PVCCFA_EHV_CPU1_DP")
		)
		(pad "2" smd rect
			(at 0.7493 0 90)
			(size 0.7112 0.8128)
			(layers "F.Cu" "F.Mask" "F.Paste")
			(net "SH_PVCCFA_EHV_CPU1")
		)
		(zone
			(layer "F.Cu")
			(hatch none 0.5)
			(connect_pads
				(clearance 0)
			)
			(min_thickness 0.25)
			(keepout
				(tracks allowed)
				(vias not_allowed)
				(pads allowed)
				(copperpour not_allowed)
				(footprints allowed)
			)
			(placement
				(enabled no)
				(sheetname "")
			)
			(fill
				(thermal_gap 0.5)
				(thermal_bridge_width 0.5)
				(island_removal_mode 0)
			)
			(polygon
				(pts
					(xy 27.130502 -134.5946) (xy 29.518102 -134.5946) (xy 29.518102 -135.412226) (xy 27.130502 -135.412226)
				)
			)
		)
	)
	(footprint ""
		(layer "F.Cu")
		(at 116.159534 -39.335456)
		(property "Reference" "R3326"
			(at 0 0 0)
			(layer "F.SilkS")
			(hide yes)
			(effects
				(font
					(size 1.27 1.27)
				)
			)
		)
		(property "Value" ""
			(at 0 0 0)
			(layer "F.Fab")
			(effects
				(font
					(size 1.27 1.27)
				)
			)
		)
		(duplicate_pad_numbers_are_jumpers no)
		(fp_line
			(start -0.7874 -0.4064)
			(end 0.7874 -0.4064)
			(stroke
				(width 0.1524)
				(type default)
			)
			(layer "F.SilkS")
		)
		(fp_line
			(start -0.7874 0.4064)
			(end -0.7874 -0.4064)
			(stroke
				(width 0.1524)
				(type default)
			)
			(layer "F.SilkS")
		)
		(fp_line
			(start 0.7874 -0.4064)
			(end 0.7874 0.4064)
			(stroke
				(width 0.1524)
				(type default)
			)
			(layer "F.SilkS")
		)
		(fp_line
			(start 0.7874 0.4064)
			(end -0.7874 0.4064)
			(stroke
				(width 0.1524)
				(type default)
			)
			(layer "F.SilkS")
		)
		(fp_line
			(start -0.67945 -0.305054)
			(end -0.12065 -0.305054)
			(stroke
				(width 0.1)
				(type default)
			)
			(layer "F.Fab")
		)
		(fp_line
			(start -0.67945 0.3048)
			(end -0.67945 -0.305054)
			(stroke
				(width 0.1)
				(type default)
			)
			(layer "F.Fab")
		)
		(fp_line
			(start -0.12065 -0.305054)
			(end -0.12065 -0.2794)
			(stroke
				(width 0.1)
				(type default)
			)
			(layer "F.Fab")
		)
		(fp_line
			(start -0.12065 -0.2794)
			(end 0.12065 -0.2794)
			(stroke
				(width 0.1)
				(type default)
			)
			(layer "F.Fab")
		)
		(fp_line
			(start -0.12065 0.2794)
			(end -0.12065 0.3048)
			(stroke
				(width 0.1)
				(type default)
			)
			(layer "F.Fab")
		)
		(fp_line
			(start -0.12065 0.3048)
			(end -0.67945 0.3048)
			(stroke
				(width 0.1)
				(type default)
			)
			(layer "F.Fab")
		)
		(fp_line
			(start 0.120396 0.2794)
			(end -0.12065 0.2794)
			(stroke
				(width 0.1)
				(type default)
			)
			(layer "F.Fab")
		)
		(fp_line
			(start 0.120396 0.3048)
			(end 0.120396 0.2794)
			(stroke
				(width 0.1)
				(type default)
			)
			(layer "F.Fab")
		)
		(fp_line
			(start 0.12065 -0.3048)
			(end 0.67945 -0.3048)
			(stroke
				(width 0.1)
				(type default)
			)
			(layer "F.Fab")
		)
		(fp_line
			(start 0.12065 -0.2794)
			(end 0.12065 -0.3048)
			(stroke
				(width 0.1)
				(type default)
			)
			(layer "F.Fab")
		)
		(fp_line
			(start 0.67945 -0.3048)
			(end 0.67945 0.3048)
			(stroke
				(width 0.1)
				(type default)
			)
			(layer "F.Fab")
		)
		(fp_line
			(start 0.67945 0.3048)
			(end 0.120396 0.3048)
			(stroke
				(width 0.1)
				(type default)
			)
			(layer "F.Fab")
		)
		(pad "1" smd circle
			(at -0.40005 0)
			(size 0 0)
			(layers "F.Cu" "F.Mask" "F.Paste")
			(net "GPU_FPGA_READY_N")
		)
		(pad "2" smd circle
			(at 0.40005 0)
			(size 0 0)
			(layers "F.Cu" "F.Mask" "F.Paste")
			(net "GPU_FPGA_READY_R_N")
		)
	)
)
